FILE_TYPE = CONNECTIVITY;
{Allegro Design Entry HDL 17.4-2019 S026 (4007227) 1/17/2022}
"PAGE_NUMBER" = 345;
0"NC";
1"P3V3_AUX\g";
2"GND\g";
3"P3V3_M2_0\g";
4"P3V3_AUX\g";
5"GND\g";
6"P3V3_AUX\g";
7"P3V3_AUX\g";
8"GND\g";
9"GND\g";
10"GND\g";
11"P3V3_AUX\g";
12"P3V3_AUX\g";
13"P3V3_AUX\g";
14"GND\g";
15"GND\g";
16"P3E_CPU1_P4_TX_C_DN<3:1>";
17"P3E_CPU1_P4_RX_DP<3:1>";
18"P3E_CPU1_P4_RX_DN<3:1>";
19"P3E_CPU1_P4_TX_C_DP<3:1>";
20"GND\g";
21"GND\g";
22"P3V3_AUX\g";
23"P3V3_M2_0\g";
24"P3V3_M2_0\g";
25"GND\g";
26"NC_M2_0_NC6";
27"NC_M2_0_NC5";
28"NC_M2_0_NC4";
29"NC_M2_0_NC3";
30"NC_M2_0_NC2";
31"NC_M2_0_NC1";
32"HDD_ACTIVITY_BUF";
33"HDD_ACTIVITY_BUF_N";
34"PU_BUFFER_HDD_ACTIVITY";
35"PD_M2_0_DEVSLP";
36"LED_HDD_ACTIVITY_B_N";
37"LED_HDD_ACTIVITY_N";
38"P3E_CPU1_P4_TX_C_DP<3>";
39"P3E_CPU1_P4_RX_DN<3>";
40"P3E_CPU1_P4_RX_DP<3>";
41"P3E_CPU1_P4_RX_DP<2>";
42"P3E_CPU1_P4_RX_DN<2>";
43"P3E_CPU1_P4_TX_C_DP<2>";
44"M2_0_PEWAKE_R_N"CDS_PHYS_NET_NAME"IRQ_LVC3_WAKE_N";
45"RST_PERST_BUF_M2_0_R_N"CDS_PHYS_NET_NAME"RST_PCIE_PCH_DEV_0_N";
46"PD_M2_0_DEVSLP"CDS_PHYS_NET_NAME"PD_M2_0_DEVSLP";
47"NC_M2_0_SUSCLK"CDS_PHYS_NET_NAME"NC_M2_0_SUSCLK";
48"NC_Q95_G2";
49"NC_Q95_S2";
50"NC_Q95_D2";
51"RST_PERST_BUF_M2_0_R_N";
52"LED_M2_SSD_0_ACT_N";
53"M2_SSD0_CLKREQ_EN_N";
54"P3E_CPU1_P4_TX_C_DP<1>";
55"P3E_CPU1_P4_TX_C_DN<1>";
56"P3E_CPU1_P4_RX_DN<1>";
57"P3E_CPU1_P4_TX_C_DN<2>";
58"NC_M2_0_NC16";
59"NC_M2_0_NC17";
60"FM_M2_SSD_0_PEDET";
61"NC_M2_0_NC19";
62"P3E_CPU1_P4_TX_C_DN<0>";
63"P3E_CPU1_P4_RX_DN<0>";
64"NC_M2_0_NC18";
65"LED_M2_SSD_0_ACT_N";
66"NC_M2_0_NC9";
67"NC_M2_0_NC8";
68"NC_M2_0_NC14";
69"NC_M2_0_NC15";
70"PU_BUFFER_HDD_ACTIVITY";
71"CLK_100M_CPU1_CLK12_DP";
72"P3E_CPU1_P4_TX_C_DP<0>";
73"P3E_CPU1_P4_RX_DP<0>";
74"SMB_M2_P1_1V8AUX_SCL"CDS_PHYS_NET_NAME"SMB_M2_P0_1V8AUX_SCL";
75"SMB_M2_P1_1V8AUX_SDA"CDS_PHYS_NET_NAME"SMB_M2_P0_1V8AUX_SDA";
76"NC_M2_0_NC11";
77"NC_M2_0_NC10";
78"NC_M2_0_NC7";
79"RST_PERST_BUF_M2_0_N"CDS_PHYS_NET_NAME"RST_PCIE_PCH_DEV_BUF_M2_0_PERST";
80"M2_0_PEWAKE_N"CDS_PHYS_NET_NAME"M2_0_PEWAKE_N";
81"CLK_100M_CPU1_CLK12_DN";
82"PCIE_M2_SSD0_PRSNT_N";
83"RST_PERST_M2_0_N"CDS_PHYS_NET_NAME"RST_PCIE_PCH_DEV_PERST_M2_R_N";
84"M2_SSD0_CLKREQ_EN_N";
85"P3E_CPU1_P4_RX_DP<1>";
86"P3E_CPU1_P4_TX_C_DN<3>";
87"M2_SSD0_CLKREQ_EN_N_BUF";
%"Q_RES"
"2","(10675,-325)","0","pure_quanta","I10";
;
LOCATION"R2121"
$SEC"1"
CDS_SEC"1"
VALUE"4.7K"
MATERIAL"CHIP"
TOLERANCE"5%"
WATTAGE"1/16W"
PACK_TYPE"0402LF"
PART_NUMBER"CS24702JB10"
CDS_LIB"pure_quanta";
"A"
$PN"1"1;
"B"
$PN"2"79;
%"UNIVERSAL_POWER"
"1","(10675,-100)","0","pure_quanta_power","I11";
;
HDL_POWER"P3V3_AUX"
CDS_LIB"pure_quanta_power";
"A"1;
%"Q_RES"
"1","(11100,-525)","0","pure_quanta","I12";
;
LOCATION"R2113"
$SEC"1"
CDS_SEC"1"
MATERIAL"CHIP"
TOLERANCE"5%"
VALUE"0"
WATTAGE"1/16W"
PACK_TYPE"0402LF"
PART_NUMBER"CS00002JB13"
CDS_LIB"pure_quanta";
"B"
$PN"2"51;
"A"
$PN"1"79;
%"UNIVERSAL_GND"
"1","(5400,2775)","0","pure_quanta_power","I14";
;
HDL_POWER"GND"
CDS_LIB"pure_quanta_power";
"A"2;
%"Q_RES"
"2","(5400,3000)","0","pure_quanta","I15";
;
LOCATION"R138"
$SEC"1"
CDS_SEC"1"
PACK_TYPE"0402LF"
WATTAGE"1/16W"
TOLERANCE"1%"
MATERIAL"EMPTY"
VALUE"4.7K"
PART_NUMBER"CS24702FB06"
CDS_LIB"pure_quanta";
"A"
$PN"1"53;
"B"
$PN"2"2;
%"Q_RES"
"1","(7025,1150)","0","pure_quanta","I19";
;
LOCATION"R3294"
$SEC"1"
CDS_SEC"1"
VALUE"0"
MATERIAL"CHIP"
TOLERANCE"5%"
PART_NUMBER"CS00002JB13"
CDS_LIB"pure_quanta"
WATTAGE"1/16W"
PACK_TYPE"0402LF";
"B"
$PN"2"37;
"A"
$PN"1"52;
%"Q_RES"
"2","(7600,1450)","0","pure_quanta","I21";
;
LOCATION"R3295"
$SEC"1"
CDS_SEC"1"
VALUE"4.7K"
TOLERANCE"1%"
PACK_TYPE"0402LF"
WATTAGE"1/16W"
MATERIAL"CHIP"
PART_NUMBER"CS24702FB06"
CDS_LIB"pure_quanta";
"A"
$PN"1"3;
"B"
$PN"2"37;
%"UNIVERSAL_POWER"
"1","(7600,1700)","0","pure_quanta_power","I22";
;
HDL_POWER"P3V3_M2_0"
CDS_LIB"pure_quanta_power";
"A"3;
%"Q_RES"
"2","(6925,2625)","0","pure_quanta","I24";
;
LOCATION"R178"
$SEC"1"
CDS_SEC"1"
VALUE"1K"
PACK_TYPE"0402LF"
TOLERANCE"1%"
WATTAGE"1/16W"
MATERIAL"CHIP"
PART_NUMBER"CS21002FB06"
CDS_LIB"pure_quanta";
"A"
$PN"1"4;
"B"
$PN"2"82;
%"UNIVERSAL_POWER"
"1","(6925,2850)","0","pure_quanta_power","I25";
;
HDL_POWER"P3V3_AUX"
CDS_LIB"pure_quanta_power";
"A"4;
%"Q_RES"
"1","(6375,3275)","0","pure_quanta","I27";
;
LOCATION"R153"
$SEC"1"
CDS_SEC"1"
TOLERANCE"5%"
MATERIAL"CHIP"
VALUE"0"
PART_NUMBER"CS00002JB13"
CDS_LIB"pure_quanta"
WATTAGE"1/16W"
PACK_TYPE"0402LF";
"B"
$PN"2"87;
"A"
$PN"1"53;
%"UNIVERSAL_GND"
"1","(8000,-1125)","0","pure_quanta_power","I3";
;
HDL_POWER"GND"
CDS_LIB"pure_quanta_power";
"A"5;
%"Q_RES"
"1","(6925,3225)","0","pure_quanta","I30";
;
LOCATION"R3301"
$SEC"1"
CDS_SEC"1"
MATERIAL"CHIP"
TOLERANCE"1%"
VALUE"33.2"
PART_NUMBER"CS03322FB03"
CDS_LIB"pure_quanta"
PACK_TYPE"0402LF"
WATTAGE"1/16W";
"B"
$PN"2"80;
"A"
$PN"1"44;
%"Q_RES"
"2","(6925,3850)","2","pure_quanta","I32";
;
LOCATION"R155"
$SEC"1"
CDS_SEC"1"
MATERIAL"EMPTY"
VALUE"1K"
WATTAGE"1/16W"
TOLERANCE"1%"
PACK_TYPE"0402LF"
PART_NUMBER"CS21002FB06"
CDS_LIB"pure_quanta";
"A"
$PN"1"6;
"B"
$PN"2"87;
%"UNIVERSAL_GND"
"1","(7925,2025)","0","pure_quanta_power","I33";
;
HDL_POWER"GND"
CDS_LIB"pure_quanta_power";
"A"20;
%"TAP"
"1","(7200,3775)","2","standard","I34";
;
HDL_TAP"TRUE"
BODY_TYPE"PLUMBING"
CDS_LIB"standard";
"B \NAC \NWC"18;
"S \NAC"
BN"1"56;
%"TAP"
"1","(7350,3825)","2","standard","I35";
;
HDL_TAP"TRUE"
BODY_TYPE"PLUMBING"
CDS_LIB"standard";
"B \NAC \NWC"17;
"S \NAC"
BN"1"85;
%"TAP"
"1","(7675,3675)","2","standard","I36";
;
HDL_TAP"TRUE"
BODY_TYPE"PLUMBING"
CDS_LIB"standard";
"B \NAC \NWC"16;
"S \NAC"
BN"1"55;
%"TAP"
"1","(7525,3725)","2","standard","I37";
;
HDL_TAP"TRUE"
BODY_TYPE"PLUMBING"
CDS_LIB"standard";
"B \NAC \NWC"19;
"S \NAC"
BN"1"54;
%"TAP"
"1","(7525,3975)","2","standard","I38";
;
HDL_TAP"TRUE"
BODY_TYPE"PLUMBING"
CDS_LIB"standard";
"B \NAC \NWC"19;
"S \NAC"
BN"2"43;
%"TAP"
"1","(7675,3925)","2","standard","I39";
;
HDL_TAP"TRUE"
BODY_TYPE"PLUMBING"
CDS_LIB"standard";
"B \NAC \NWC"16;
"S \NAC"
BN"2"57;
%"UNIVERSAL_GND"
"1","(7200,-675)","0","pure_quanta_power","I4";
;
HDL_POWER"GND"
CDS_LIB"pure_quanta_power";
"A"21;
%"UNIVERSAL_POWER"
"1","(6925,4075)","0","pure_quanta_power","I44";
;
HDL_POWER"P3V3_AUX"
CDS_LIB"pure_quanta_power";
"A"6;
%"TAP"
"1","(7200,4025)","2","standard","I45";
;
HDL_TAP"TRUE"
BODY_TYPE"PLUMBING"
CDS_LIB"standard";
"B \NAC \NWC"18;
"S \NAC"
BN"2"42;
%"TAP"
"1","(7200,4275)","2","standard","I46";
;
HDL_TAP"TRUE"
BODY_TYPE"PLUMBING"
CDS_LIB"standard";
"B \NAC \NWC"18;
"S \NAC"
BN"3"39;
%"TAP"
"1","(7350,4075)","2","standard","I47";
;
HDL_TAP"TRUE"
BODY_TYPE"PLUMBING"
CDS_LIB"standard";
"B \NAC \NWC"17;
"S \NAC"
BN"2"41;
%"TAP"
"1","(7350,4325)","2","standard","I48";
;
HDL_TAP"TRUE"
BODY_TYPE"PLUMBING"
CDS_LIB"standard";
"B \NAC \NWC"17;
"S \NAC"
BN"3"40;
%"TAP"
"1","(7525,4225)","2","standard","I49";
;
HDL_TAP"TRUE"
BODY_TYPE"PLUMBING"
CDS_LIB"standard";
"B \NAC \NWC"19;
"S \NAC"
BN"3"38;
%"SN74LVC2G07DCKR"
"1","(7625,-475)","0","pure_quanta","I5";
;
LOCATION"U259"
$SEC"1"
CDS_SEC"1"
VALUE"SN74LVC2G07DCKR"
MATERIAL"IC"
PACK_TYPE"SMLF"
PART_NUMBER"AL002G07006"
CDS_LIB"pure_quanta"
NEEDS_NO_SIZE"TRUE";
"VCC"
$PN"5"12;
"GND"
$PN"2"21;
"2Y"
$PN"4"79;
"1Y"
$PN"6"32;
"2A"
$PN"3"83;
"1A"
$PN"1"84;
%"TAP"
"1","(7675,4175)","2","standard","I50";
;
HDL_TAP"TRUE"
BODY_TYPE"PLUMBING"
CDS_LIB"standard";
"B \NAC \NWC"16;
"S \NAC"
BN"3"86;
%"Q_RES"
"2","(8575,225)","0","pure_quanta","I51";
;
LOCATION"R3296"
$SEC"1"
CDS_SEC"1"
PACK_TYPE"0402LF"
TOLERANCE"1%"
VALUE"4.7K"
WATTAGE"1/16W"
MATERIAL"CHIP"
PART_NUMBER"CS24702FB06"
CDS_LIB"pure_quanta";
"A"
$PN"1"7;
"B"
$PN"2"32;
%"UNIVERSAL_POWER"
"1","(8575,550)","0","pure_quanta_power","I52";
;
HDL_POWER"P3V3_AUX"
CDS_LIB"pure_quanta_power";
"A"7;
%"74LVC1G126SE7"
"1","(9300,1100)","0","pure_quanta","I53";
;
LOCATION"U239"
$SEC"1"
CDS_SEC"1"
MATERIAL"IC"
PART_TYPE"SMLF"
VALUE"74LVC1G126SE-7"
PART_NUMBER"AL1G0126009"
NEEDS_NO_SIZE"TRUE"
CDS_LMAN_SYM_OUTLINE"-100,100,100,-100"
CDS_LIB"pure_quanta";
"OE"
$PN"1"70;
"GND"
$PN"3"8;
"VCC"
$PN"5"22;
"Y"
$PN"4"36;
"A"
$PN"2"37;
%"UNIVERSAL_GND"
"1","(9300,700)","0","pure_quanta_power","I54";
;
HDL_POWER"GND"
CDS_LIB"pure_quanta_power";
"A"8;
%"UNIVERSAL_GND"
"1","(9550,1200)","0","pure_quanta_power","I55";
;
HDL_POWER"GND"
CDS_LIB"pure_quanta_power";
"A"9;
%"Q_CAP"
"1","(9550,1450)","0","pure_quanta","I56";
;
LOCATION"C1873"
$SEC"1"
CDS_SEC"1"
MATERIAL"X7R"
VALUE"0.1UF"
PACK_TYPE"0402"
TOLERANCE"10%"
VOLTAGE"25V"
PART_NUMBER"CH4104K1B00"
BOM_COST"VR_SYSTEM "
CDS_LIB"pure_quanta";
"B"
$PN"2"9;
"A"
$PN"1"22;
%"UNIVERSAL_POWER"
"1","(9300,1800)","0","pure_quanta_power","I57";
;
HDL_POWER"P3V3_AUX"
CDS_LIB"pure_quanta_power";
"A"22;
%"Q_RES"
"2","(10675,425)","2","pure_quanta","I58";
;
LOCATION"R3298"
$SEC"1"
CDS_SEC"1"
VALUE"10K"
PACK_TYPE"0402LF"
MATERIAL"CHIP"
TOLERANCE"1%"
WATTAGE"1/16W"
PART_NUMBER"CS31002FB08"
CDS_LIB"pure_quanta";
"A"
$PN"1"11;
"B"
$PN"2"33;
%"UNIVERSAL_GND"
"1","(10250,600)","0","pure_quanta_power","I59";
;
HDL_POWER"GND"
CDS_LIB"pure_quanta_power";
"A"10;
%"Q_CAP"
"1","(8000,-825)","0","pure_quanta","I6";
;
LOCATION"C2007"
$SEC"1"
CDS_SEC"1"
PACK_TYPE"C0402"
MATERIAL"X6S"
VOLTAGE"25V"
TOLERANCE"10%"
VALUE"1UF"
PART_NUMBER"CH5104KEB02"
CDS_LIB"pure_quanta"
BOM_COST"VR_SYSTEM ";
"B"
$PN"2"5;
"A"
$PN"1"12;
%"Q_RES"
"2","(10250,850)","2","pure_quanta","I60";
;
LOCATION"R3297"
$SEC"1"
CDS_SEC"1"
VALUE"10K"
PACK_TYPE"0402LF"
MATERIAL"CHIP"
WATTAGE"1/16W"
TOLERANCE"1%"
PART_NUMBER"CS31002FB08"
CDS_LIB"pure_quanta";
"A"
$PN"1"36;
"B"
$PN"2"10;
%"UNIVERSAL_POWER"
"1","(10675,625)","0","pure_quanta_power","I61";
;
HDL_POWER"P3V3_AUX"
CDS_LIB"pure_quanta_power";
"A"11;
%"Q_RES"
"1","(10950,175)","0","pure_quanta","I62";
;
LOCATION"R5377"
$SEC"1"
CDS_SEC"1"
TOLERANCE"5%"
PACK_TYPE"0402LF"
WATTAGE"1/16W"
VALUE"0"
MATERIAL"CHIP"
PART_NUMBER"CS00002JB13"
CDS_LIB"pure_quanta";
"B"
$PN"2"34;
"A"
$PN"1"33;
%"Q_RES"
"1","(10550,3200)","0","pure_quanta","I66";
;
LOCATION"R1396"
$SEC"1"
CDS_SEC"1"
WATTAGE"1/16W"
TOLERANCE"1%"
MATERIAL"CHIP"
PACK_TYPE"0402LF"
VALUE"10K"
PART_NUMBER"CS31002FB08"
CDS_LIB"pure_quanta";
"B"
$PN"2"13;
"A"
$PN"1"60;
%"UNIVERSAL_POWER"
"1","(8000,-275)","0","pure_quanta_power","I7";
;
HDL_POWER"P3V3_AUX"
CDS_LIB"pure_quanta_power";
"A"12;
%"UNIVERSAL_POWER"
"1","(11125,3275)","0","pure_quanta_power","I73";
;
HDL_POWER"P3V3_AUX"
CDS_LIB"pure_quanta_power";
"A"13;
%"UNIVERSAL_POWER"
"1","(9425,4575)","0","pure_quanta_power","I75";
;
HDL_POWER"P3V3_M2_0"
CDS_LIB"pure_quanta_power";
"A"23;
%"UNIVERSAL_POWER"
"1","(11225,4575)","0","pure_quanta_power","I76";
;
HDL_POWER"P3V3_M2_0"
CDS_LIB"pure_quanta_power";
"A"24;
%"Q_CAP"
"1","(11225,4200)","0","pure_quanta","I77";
;
LOCATION"C1920"
$SEC"1"
CDS_SEC"1"
VOLTAGE"6.3V"
VALUE"22UF"
MATERIAL"X6S"
PACK_TYPE"C0603"
TOLERANCE"20%"
PART_NUMBER"CH6221ME900"
CDS_LIB"pure_quanta";
"B"
$PN"2"25;
"A"
$PN"1"24;
%"Q_CAP"
"1","(11625,4200)","0","pure_quanta","I78";
;
LOCATION"C1921"
$SEC"1"
CDS_SEC"1"
VALUE"22UF"
PACK_TYPE"C0603"
MATERIAL"X6S"
TOLERANCE"20%"
VOLTAGE"6.3V"
PART_NUMBER"CH6221ME900"
CDS_LIB"pure_quanta";
"B"
$PN"2"25;
"A"
$PN"1"24;
%"Q_CAP"
"1","(12025,4200)","0","pure_quanta","I79";
;
LOCATION"C9922"
$SEC"1"
CDS_SEC"1"
VALUE"22UF"
TOLERANCE"20%"
VOLTAGE"6.3V"
PACK_TYPE"C0603"
MATERIAL"X6S"
PART_NUMBER"CH6221ME900"
CDS_LIB"pure_quanta";
"B"
$PN"2"25;
"A"
$PN"1"24;
%"MOSFET_NCH_DUAL"
"1","(9750,-125)","0","pure_quanta","I8";
;
LOCATION"Q95"
SEC"1"
MATERIAL"IC"
PART_TYPE"SMLF"
VALUE"PJT138K"
PART_NUMBER"BAM138K0003"
NEEDS_NO_SIZE"TRUE"
SEC_TYPE""
CDS_LMAN_SYM_OUTLINE"-150,150,150,-150"
CDS_LIB"pure_quanta";
"D1"
$PN"6"33;
"G1"
$PN"2"32;
"S1"
$PN"1"15;
%"UNIVERSAL_GND"
"1","(13225,3850)","0","pure_quanta_power","I81";
;
HDL_POWER"GND"
CDS_LIB"pure_quanta_power"
CATEGORY"LED";
"A"25;
%"UNIVERSAL_GND"
"1","(13300,2575)","0","pure_quanta_power","I82";
;
HDL_POWER"GND"
CDS_LIB"pure_quanta_power";
"A"14;
%"Q_RES"
"2","(13300,2825)","0","pure_quanta","I83";
;
LOCATION"R1605"
$SEC"1"
CDS_SEC"1"
MATERIAL"CHIP"
WATTAGE"1/16W"
TOLERANCE"1%"
VALUE"1K"
PACK_TYPE"0402LF"
PART_NUMBER"CS21002FB06"
CDS_LIB"pure_quanta";
"A"
$PN"1"35;
"B"
$PN"2"14;
%"Q_CAP"
"1","(12425,4200)","0","pure_quanta","I84";
;
LOCATION"C1923"
$SEC"1"
CDS_SEC"1"
VOLTAGE"25V"
VALUE"0.1UF"
MATERIAL"X7R"
TOLERANCE"10%"
PACK_TYPE"0402"
PART_NUMBER"CH4104K1B00"
CDS_LIB"pure_quanta";
"B"
$PN"2"25;
"A"
$PN"1"24;
%"Q_CAP"
"1","(12825,4200)","0","pure_quanta","I85";
;
LOCATION"C1924"
$SEC"1"
CDS_SEC"1"
PACK_TYPE"0402"
VALUE"0.1UF"
MATERIAL"X7R"
VOLTAGE"25V"
TOLERANCE"10%"
PART_NUMBER"CH4104K1B00"
CDS_LIB"pure_quanta";
"B"
$PN"2"25;
"A"
$PN"1"24;
%"Q_CAP"
"1","(13225,4200)","0","pure_quanta","I86";
;
LOCATION"C1925"
$SEC"1"
CDS_SEC"1"
TOLERANCE"10%"
VOLTAGE"25V"
PACK_TYPE"0402"
MATERIAL"X7R"
VALUE"0.1UF"
PART_NUMBER"CH4104K1B00"
CDS_LIB"pure_quanta";
"B"
$PN"2"25;
"A"
$PN"1"24;
%"SCONN75K_APCI0155P004A"
"1","(8675,3250)","2","pure_quanta","I88";
;
LOCATION"J59"
$SEC"1"
CDS_SEC"1"
VALUE"SCONN75K_APCI0155-P004A"
PART_TYPE"SMLF"
MATERIAL"EMPTY"
PART_NUMBER"DFHS75FR313"
CDS_LIB"pure_quanta"
CDS_LMAN_SYM_OUTLINE"-450,1125,450,-1125"
PIN_NAMES_ROTATE"True";
"REFCLKP"
$PN"55"71;
"REFCLKN"
$PN"53"81;
"PETP1"
$PN"37"54;
"PETN1"
$PN"35"55;
"PERP1"
$PN"31"85;
"PERN1"
$PN"29"56;
"PETP2"
$PN"25"43;
"PETN2"
$PN"23"57;
"PERP2"
$PN"19"41;
"PERN2"
$PN"17"42;
"PETP3"
$PN"13"38;
"PETN3"
$PN"11"86;
"PERP3"
$PN"7"40;
"PERN3"
$PN"5"39;
"GND10"
$PN"51"20;
"GND9"
$PN"45"20;
"GND8"
$PN"39"20;
"GND7"
$PN"33"20;
"GND6"
$PN"27"20;
"GND5"
$PN"21"20;
"GND4"
$PN"15"20;
"GND3"
$PN"9"20;
"GND2"
$PN"3"20;
"GND1"
$PN"1"82;
"NC4"
$PN"22"28;
"NC5"
$PN"24"27;
"NC6"
$PN"26"26;
"NC7"
$PN"28"78;
"NC8"
$PN"30"67;
"NC9"
$PN"32"66;
"NC11"
$PN"36"76;
"NC12"
$PN"40"74;
"NC13"
$PN"42"75;
"NC14"
$PN"44"68;
"NC15"
$PN"46"69;
"NC16"
$PN"48"58;
"NC17"
$PN"56"59;
"NC10"
$PN"34"77;
"NC3"
$PN"20"29;
"NC2"
$PN"8"30;
"NC1"
$PN"6"31;
"G2"
$PN"G2"20;
"G1"
$PN"G1"20;
"GND14"
$PN"75"20;
"GND13"
$PN"73"20;
"GND12"
$PN"71"20;
"PEDET"
$PN"69"60;
"NC19"
$PN"67"61;
"GND11"
$PN"57"20;
"PETP0||SATA-A+"
$PN"49"72;
"PETN0||SATA-A-"
$PN"47"62;
"PERP0||SATA-B-"
$PN"43"73;
"PERN0||SATA-B+"
$PN"41"63;
"3.3V_9"
$PN"74"23;
"3.3V_8"
$PN"72"23;
"3.3V_7"
$PN"70"23;
"SUSCLK"
$PN"68"47;
"NC18"
$PN"58"64;
"PEWAKE# \B"
$PN"54"80;
"CLKREQ# \B"
$PN"52"87;
"PERST# \B"
$PN"50"45;
"DEVSLP"
$PN"38"46;
"3.3V_6"
$PN"18"23;
"3.3V_5"
$PN"16"23;
"3.3V_4"
$PN"14"23;
"3.3V_3"
$PN"12"23;
"DAS_DSS#||LED1#"
$PN"10"65;
"3.3V_2"
$PN"4"23;
"3.3V_1"
$PN"2"23;
%"MOSFET_NCH_DUAL"
"2","(10400,-800)","0","pure_quanta","I89";
;
LOCATION"Q95"
$SEC"2"
CDS_SEC"2"
MATERIAL"IC"
PART_TYPE"SMLF"
VALUE"PJT138K"
PART_NUMBER"BAM138K0003"
CDS_LMAN_SYM_OUTLINE"-150,150,150,-150"
NEEDS_NO_SIZE"TRUE"
CDS_LIB"pure_quanta";
"S2"
$PN"4"49;
"G2"
$PN"5"48;
"D2"
$PN"3"50;
%"UNIVERSAL_GND"
"1","(9800,-475)","0","pure_quanta_power","I9";
;
HDL_POWER"GND"
CDS_LIB"pure_quanta_power";
"A"15;
END.
